(kicad_pcb
	(version 20241229)
	(generator "pcbnew")
	(generator_version "9.0")
	(general
		(thickness 1.61)
		(legacy_teardrops no)
	)
	(paper "A3")
	(title_block
		(title "RDIMM DDR5 Tester")
		(date "2026-05-21")
		(rev "2.2.0")
		(company "Antmicro")
		(comment 9 "footprint 119 of 796 (U34), pads 466-536 of 676")
	)
	(layers
		(0 "F.Cu" signal)
		(4 "In1.Cu" power)
		(6 "In2.Cu" mixed)
		(8 "In3.Cu" power)
		(10 "In4.Cu" mixed)
		(12 "In5.Cu" power)
		(14 "In6.Cu" mixed)
		(16 "In7.Cu" power)
		(18 "In8.Cu" power)
		(20 "In9.Cu" mixed)
		(22 "In10.Cu" power)
		(2 "B.Cu" signal)
		(9 "F.Adhes" user "F.Adhesive")
		(11 "B.Adhes" user "B.Adhesive")
		(13 "F.Paste" user)
		(15 "B.Paste" user)
		(5 "F.SilkS" user "F.Silkscreen")
		(7 "B.SilkS" user "B.Silkscreen")
		(1 "F.Mask" user)
		(3 "B.Mask" user)
		(17 "Dwgs.User" user "User.Drawings")
		(19 "Cmts.User" user "User.Comments")
		(21 "Eco1.User" user "User.Eco1")
		(23 "Eco2.User" user "User.Eco2")
		(25 "Edge.Cuts" user)
		(27 "Margin" user)
		(31 "F.CrtYd" user "F.Courtyard")
		(29 "B.CrtYd" user "B.Courtyard")
		(35 "F.Fab" user)
		(33 "B.Fab" user)
	)
	(footprint "antmicro-footprints:BGA-676_27x27mm_Layout26x26_P1x1mm_FFVB676"
		(layer "F.Cu")
		(at 188.5 152.5 90)
		(property "Reference" "U34"
			(at -14.72 12.46 180)
			(layer "F.SilkS")
			(effects
				(font
					(size 0.7 0.7)
					(thickness 0.15)
				)
				(justify left bottom)
			)
		)
		(property "Value" "XCAU25P-2FFVB676I"
			(at 0 15.5 90)
			(layer "F.Fab")
			(effects
				(font
					(size 0.7 0.7)
					(thickness 0.15)
				)
				(justify left bottom)
			)
		)
		(property "Datasheet" "https://docs.xilinx.com/viewer/book-attachment/2PXOpPtpaABIt0fkzeBLnw/hvbsEUaOT0OxFhln7VEVyA"
			(at 0 0 90)
			(layer "F.Fab")
			(hide yes)
			(effects
				(font
					(size 1.27 1.27)
					(thickness 0.15)
				)
			)
		)
		(property "MPN" "XCAU25P-2FFVB676I"
			(at 0 0 90)
			(unlocked yes)
			(layer "F.Fab")
			(hide yes)
			(effects
				(font
					(size 1 1)
					(thickness 0.15)
				)
			)
		)
		(property "Manufacturer" "AMD-Xilinx"
			(at 0 0 90)
			(unlocked yes)
			(layer "F.Fab")
			(hide yes)
			(effects
				(font
					(size 1 1)
					(thickness 0.15)
				)
			)
		)
		(property "Author" "Antmicro"
			(at 0 0 90)
			(unlocked yes)
			(layer "F.Fab")
			(hide yes)
			(effects
				(font
					(size 1 1)
					(thickness 0.15)
				)
			)
		)
		(property "License" "Apache-2.0"
			(at 0 0 90)
			(unlocked yes)
			(layer "F.Fab")
			(hide yes)
			(effects
				(font
					(size 1 1)
					(thickness 0.15)
				)
			)
		)
		(sheetname "/FPGA Config/")
		(sheetfile "fpga-config.kicad_sch")
		(attr smd)
		(pad "M24" smd circle
			(at 10.5 -1.5 90)
			(size 0.5 0.5)
			(layers "F.Cu" "F.Mask" "F.Paste")
			(net 556 "unconnected-(U34D-IO_T1U_N12_66-PadM24)")
			(pinfunction "IO_T1U_N12_66")
			(pintype "bidirectional+no_connect")
			(die_length 9.663)
			(solder_mask_margin 0.075)
		)
		(pad "M25" smd circle
			(at 11.5 -1.5 90)
			(size 0.5 0.5)
			(layers "F.Cu" "F.Mask" "F.Paste")
			(net 113 "/DDR5 RDIMM/B.DQ9")
			(pinfunction "IO_L8P_T1L_N2_AD5P_66")
			(pintype "bidirectional")
			(die_length 12.154)
			(solder_mask_margin 0.075)
		)
		(pad "M26" smd circle
			(at 12.5 -1.5 90)
			(size 0.5 0.5)
			(layers "F.Cu" "F.Mask" "F.Paste")
			(net 112 "/DDR5 RDIMM/B.DQ8")
			(pinfunction "IO_L8N_T1L_N3_AD5N_66")
			(pintype "bidirectional")
			(die_length 12.064)
			(solder_mask_margin 0.075)
		)
		(pad "N1" smd circle
			(at -12.5 -0.5 90)
			(size 0.5 0.5)
			(layers "F.Cu" "F.Mask" "F.Paste")
			(net 1 "GND")
			(pinfunction "GND")
			(pintype "passive")
			(solder_mask_margin 0.075)
		)
		(pad "N2" smd circle
			(at -11.5 -0.5 90)
			(size 0.5 0.5)
			(layers "F.Cu" "F.Mask" "F.Paste")
			(net 1 "GND")
			(pinfunction "GND")
			(pintype "passive")
			(solder_mask_margin 0.075)
		)
		(pad "N3" smd circle
			(at -10.5 -0.5 90)
			(size 0.5 0.5)
			(layers "F.Cu" "F.Mask" "F.Paste")
			(net 1 "GND")
			(pinfunction "GND")
			(pintype "passive")
			(solder_mask_margin 0.075)
		)
		(pad "N4" smd circle
			(at -9.5 -0.5 90)
			(size 0.5 0.5)
			(layers "F.Cu" "F.Mask" "F.Paste")
			(net 631 "/FPGA MGT Interface/HDMI_FPGA.TX0_N")
			(pinfunction "MGTYTXN0_226")
			(pintype "output")
			(die_length 7.485)
			(solder_mask_margin 0.075)
		)
		(pad "N5" smd circle
			(at -8.5 -0.5 90)
			(size 0.5 0.5)
			(layers "F.Cu" "F.Mask" "F.Paste")
			(net 632 "/FPGA MGT Interface/HDMI_FPGA.TX0_P")
			(pinfunction "MGTYTXP0_226")
			(pintype "output")
			(die_length 7.498)
			(solder_mask_margin 0.075)
		)
		(pad "N6" smd circle
			(at -7.5 -0.5 90)
			(size 0.5 0.5)
			(layers "F.Cu" "F.Mask" "F.Paste")
			(net 1 "GND")
			(pinfunction "GND")
			(pintype "passive")
			(solder_mask_margin 0.075)
		)
		(pad "N7" smd circle
			(at -6.5 -0.5 90)
			(size 0.5 0.5)
			(layers "F.Cu" "F.Mask" "F.Paste")
			(net 820 "+0V9_MGTAVCC")
			(pinfunction "MGTAVCC_R")
			(pintype "passive")
			(solder_mask_margin 0.075)
		)
		(pad "N8" smd circle
			(at -5.5 -0.5 90)
			(size 0.5 0.5)
			(layers "F.Cu" "F.Mask" "F.Paste")
			(net 1 "GND")
			(pinfunction "GND")
			(pintype "passive")
			(solder_mask_margin 0.075)
		)
		(pad "N9" smd circle
			(at -4.5 -0.5 90)
			(size 0.5 0.5)
			(layers "F.Cu" "F.Mask" "F.Paste")
			(net 553 "+0V85")
			(pinfunction "VCCINT_IO")
			(pintype "passive")
			(solder_mask_margin 0.075)
		)
		(pad "N10" smd circle
			(at -3.5 -0.5 90)
			(size 0.5 0.5)
			(layers "F.Cu" "F.Mask" "F.Paste")
			(net 553 "+0V85")
			(pinfunction "VCCINT")
			(pintype "passive")
			(solder_mask_margin 0.075)
		)
		(pad "N11" smd circle
			(at -2.5 -0.5 90)
			(size 0.5 0.5)
			(layers "F.Cu" "F.Mask" "F.Paste")
			(net 1 "GND")
			(pinfunction "GND")
			(pintype "passive")
			(solder_mask_margin 0.075)
		)
		(pad "N12" smd circle
			(at -1.5 -0.5 90)
			(size 0.5 0.5)
			(layers "F.Cu" "F.Mask" "F.Paste")
			(net 553 "+0V85")
			(pinfunction "VCCINT")
			(pintype "passive")
			(solder_mask_margin 0.075)
		)
		(pad "N13" smd circle
			(at -0.5 -0.5 90)
			(size 0.5 0.5)
			(layers "F.Cu" "F.Mask" "F.Paste")
			(net 1 "GND")
			(pinfunction "GNDADC")
			(pintype "input")
			(die_length 9.132)
			(solder_mask_margin 0.075)
		)
		(pad "N14" smd circle
			(at 0.5 -0.5 90)
			(size 0.5 0.5)
			(layers "F.Cu" "F.Mask" "F.Paste")
			(net 797 "+1V8")
			(pinfunction "VCCADC")
			(pintype "power_in")
			(die_length 9.369)
			(solder_mask_margin 0.075)
		)
		(pad "N15" smd circle
			(at 1.5 -0.5 90)
			(size 0.5 0.5)
			(layers "F.Cu" "F.Mask" "F.Paste")
			(net 1 "GND")
			(pinfunction "GND")
			(pintype "passive")
			(solder_mask_margin 0.075)
		)
		(pad "N16" smd circle
			(at 2.5 -0.5 90)
			(size 0.5 0.5)
			(layers "F.Cu" "F.Mask" "F.Paste")
			(net 553 "+0V85")
			(pinfunction "VCCINT")
			(pintype "passive")
			(solder_mask_margin 0.075)
		)
		(pad "N17" smd circle
			(at 3.5 -0.5 90)
			(size 0.5 0.5)
			(layers "F.Cu" "F.Mask" "F.Paste")
			(net 1 "GND")
			(pinfunction "GND")
			(pintype "passive")
			(solder_mask_margin 0.075)
		)
		(pad "N18" smd circle
			(at 4.5 -0.5 90)
			(size 0.5 0.5)
			(layers "F.Cu" "F.Mask" "F.Paste")
			(net 797 "+1V8")
			(pinfunction "VCCAUX")
			(pintype "passive")
			(solder_mask_margin 0.075)
		)
		(pad "N19" smd circle
			(at 5.5 -0.5 90)
			(size 0.5 0.5)
			(layers "F.Cu" "F.Mask" "F.Paste")
			(net 211 "/DDR5 RDIMM/B.CB3")
			(pinfunction "IO_L23P_T3U_N8_I2C_SCLK_65")
			(pintype "bidirectional")
			(die_length 10.827)
			(solder_mask_margin 0.075)
		)
		(pad "N20" smd circle
			(at 6.5 -0.5 90)
			(size 0.5 0.5)
			(layers "F.Cu" "F.Mask" "F.Paste")
			(net 1 "GND")
			(pinfunction "GND")
			(pintype "passive")
			(solder_mask_margin 0.075)
		)
		(pad "N21" smd circle
			(at 7.5 -0.5 90)
			(size 0.5 0.5)
			(layers "F.Cu" "F.Mask" "F.Paste")
			(net 105 "/DDR5 RDIMM/B.CB1")
			(pinfunction "IO_L24P_T3U_N10_EMCCLK_65")
			(pintype "bidirectional")
			(die_length 10.865)
			(solder_mask_margin 0.075)
		)
		(pad "N22" smd circle
			(at 8.5 -0.5 90)
			(size 0.5 0.5)
			(layers "F.Cu" "F.Mask" "F.Paste")
			(net 210 "/DDR5 RDIMM/B.CB2")
			(pinfunction "IO_L24N_T3U_N11_DOUT_CSO_B_65")
			(pintype "bidirectional")
			(die_length 10.705)
			(solder_mask_margin 0.075)
		)
		(pad "N23" smd circle
			(at 9.5 -0.5 90)
			(size 0.5 0.5)
			(layers "F.Cu" "F.Mask" "F.Paste")
			(net 452 "/DDR5 RDIMM/B.DQS4_P")
			(pinfunction "IO_L22P_T3U_N6_DBC_AD0P_D04_65")
			(pintype "bidirectional")
			(die_length 10.749)
			(solder_mask_margin 0.075)
		)
		(pad "N24" smd circle
			(at 10.5 -0.5 90)
			(size 0.5 0.5)
			(layers "F.Cu" "F.Mask" "F.Paste")
			(net 82 "/DDR5 RDIMM/B.CA6")
			(pinfunction "IO_L15P_T2L_N4_AD11P_A02_D18_65")
			(pintype "bidirectional")
			(die_length 12.454)
			(solder_mask_margin 0.075)
		)
		(pad "N25" smd circle
			(at 11.5 -0.5 90)
			(size 0.5 0.5)
			(layers "F.Cu" "F.Mask" "F.Paste")
			(net 1 "GND")
			(pinfunction "GND")
			(pintype "passive")
			(solder_mask_margin 0.075)
		)
		(pad "N26" smd circle
			(at 12.5 -0.5 90)
			(size 0.5 0.5)
			(layers "F.Cu" "F.Mask" "F.Paste")
			(net 602 "/DDR5 RDIMM/CTRL.PWR_GOOD")
			(pinfunction "IO_T2U_N12_CSI_ADV_B_65")
			(pintype "bidirectional")
			(die_length 11.605)
			(solder_mask_margin 0.075)
		)
		(pad "P1" smd circle
			(at -12.5 0.5 90)
			(size 0.5 0.5)
			(layers "F.Cu" "F.Mask" "F.Paste")
			(net 333 "/FPGA MGT Interface/PCIE.RXD0_N")
			(pinfunction "MGTYRXN3_225")
			(pintype "input")
			(die_length 9.421)
			(solder_mask_margin 0.075)
		)
		(pad "P2" smd circle
			(at -11.5 0.5 90)
			(size 0.5 0.5)
			(layers "F.Cu" "F.Mask" "F.Paste")
			(net 332 "/FPGA MGT Interface/PCIE.RXD0_P")
			(pinfunction "MGTYRXP3_225")
			(pintype "input")
			(die_length 9.419)
			(solder_mask_margin 0.075)
		)
		(pad "P3" smd circle
			(at -10.5 0.5 90)
			(size 0.5 0.5)
			(layers "F.Cu" "F.Mask" "F.Paste")
			(net 1 "GND")
			(pinfunction "GND")
			(pintype "passive")
			(solder_mask_margin 0.075)
		)
		(pad "P4" smd circle
			(at -9.5 0.5 90)
			(size 0.5 0.5)
			(layers "F.Cu" "F.Mask" "F.Paste")
			(net 1 "GND")
			(pinfunction "GND")
			(pintype "passive")
			(solder_mask_margin 0.075)
		)
		(pad "P5" smd circle
			(at -8.5 0.5 90)
			(size 0.5 0.5)
			(layers "F.Cu" "F.Mask" "F.Paste")
			(net 172 "+1V2_MGTAVTT")
			(pinfunction "MGTAVTT_R")
			(pintype "passive")
			(solder_mask_margin 0.075)
		)
		(pad "P6" smd circle
			(at -7.5 0.5 90)
			(size 0.5 0.5)
			(layers "F.Cu" "F.Mask" "F.Paste")
			(net 387 "/FPGA MGT Interface/HDMI_SI5319_CLK_N")
			(pinfunction "MGTREFCLK0N_226")
			(pintype "input")
			(die_length 6.1)
			(solder_mask_margin 0.075)
		)
		(pad "P7" smd circle
			(at -6.5 0.5 90)
			(size 0.5 0.5)
			(layers "F.Cu" "F.Mask" "F.Paste")
			(net 402 "/FPGA MGT Interface/HDMI_SI5319_CLK_P")
			(pinfunction "MGTREFCLK0P_226")
			(pintype "input")
			(die_length 6.016)
			(solder_mask_margin 0.075)
		)
		(pad "P8" smd circle
			(at -5.5 0.5 90)
			(size 0.5 0.5)
			(layers "F.Cu" "F.Mask" "F.Paste")
			(net 1 "GND")
			(pinfunction "GND")
			(pintype "passive")
			(solder_mask_margin 0.075)
		)
		(pad "P9" smd circle
			(at -4.5 0.5 90)
			(size 0.5 0.5)
			(layers "F.Cu" "F.Mask" "F.Paste")
			(net 553 "+0V85")
			(pinfunction "VCCINT_IO")
			(pintype "passive")
			(solder_mask_margin 0.075)
		)
		(pad "P10" smd circle
			(at -3.5 0.5 90)
			(size 0.5 0.5)
			(layers "F.Cu" "F.Mask" "F.Paste")
			(net 1 "GND")
			(pinfunction "GND")
			(pintype "passive")
			(solder_mask_margin 0.075)
		)
		(pad "P11" smd circle
			(at -2.5 0.5 90)
			(size 0.5 0.5)
			(layers "F.Cu" "F.Mask" "F.Paste")
			(net 553 "+0V85")
			(pinfunction "VCCINT")
			(pintype "passive")
			(solder_mask_margin 0.075)
		)
		(pad "P12" smd circle
			(at -1.5 0.5 90)
			(size 0.5 0.5)
			(layers "F.Cu" "F.Mask" "F.Paste")
			(net 1 "GND")
			(pinfunction "GND")
			(pintype "passive")
			(solder_mask_margin 0.075)
		)
		(pad "P13" smd circle
			(at -0.5 0.5 90)
			(size 0.5 0.5)
			(layers "F.Cu" "F.Mask" "F.Paste")
			(net 598 "/FPGA Config/VREFN")
			(pinfunction "VREFN")
			(pintype "input")
			(die_length 9.331)
			(solder_mask_margin 0.075)
		)
		(pad "P14" smd circle
			(at 0.5 0.5 90)
			(size 0.5 0.5)
			(layers "F.Cu" "F.Mask" "F.Paste")
			(net 1 "GND")
			(pinfunction "VP")
			(pintype "input")
			(die_length 10.149)
			(solder_mask_margin 0.075)
		)
		(pad "P15" smd circle
			(at 1.5 0.5 90)
			(size 0.5 0.5)
			(layers "F.Cu" "F.Mask" "F.Paste")
			(net 553 "+0V85")
			(pinfunction "VCCINT")
			(pintype "passive")
			(solder_mask_margin 0.075)
		)
		(pad "P16" smd circle
			(at 2.5 0.5 90)
			(size 0.5 0.5)
			(layers "F.Cu" "F.Mask" "F.Paste")
			(net 1 "GND")
			(pinfunction "GND")
			(pintype "passive")
			(solder_mask_margin 0.075)
		)
		(pad "P17" smd circle
			(at 3.5 0.5 90)
			(size 0.5 0.5)
			(layers "F.Cu" "F.Mask" "F.Paste")
			(net 553 "+0V85")
			(pinfunction "VCCINT")
			(pintype "passive")
			(solder_mask_margin 0.075)
		)
		(pad "P18" smd circle
			(at 4.5 0.5 90)
			(size 0.5 0.5)
			(layers "F.Cu" "F.Mask" "F.Paste")
			(net 797 "+1V8")
			(pinfunction "VCCAUX_IO")
			(pintype "power_in")
			(solder_mask_margin 0.075)
		)
		(pad "P19" smd circle
			(at 5.5 0.5 90)
			(size 0.5 0.5)
			(layers "F.Cu" "F.Mask" "F.Paste")
			(net 103 "/DDR5 RDIMM/B.CB0")
			(pinfunction "IO_L23N_T3U_N9_PERSTN1_I2C_SDA_65")
			(pintype "bidirectional")
			(die_length 11.001)
			(solder_mask_margin 0.075)
		)
		(pad "P20" smd circle
			(at 6.5 0.5 90)
			(size 0.5 0.5)
			(layers "F.Cu" "F.Mask" "F.Paste")
			(net 99 "/DDR5 RDIMM/B.CB4")
			(pinfunction "IO_L20P_T3L_N2_AD1P_D08_65")
			(pintype "bidirectional")
			(die_length 10.644)
			(solder_mask_margin 0.075)
		)
		(pad "P21" smd circle
			(at 7.5 0.5 90)
			(size 0.5 0.5)
			(layers "F.Cu" "F.Mask" "F.Paste")
			(net 205 "/DDR5 RDIMM/B.CB7")
			(pinfunction "IO_L20N_T3L_N3_AD1N_D09_65")
			(pintype "bidirectional")
			(die_length 10.758)
			(solder_mask_margin 0.075)
		)
		(pad "P22" smd circle
			(at 8.5 0.5 90)
			(size 0.5 0.5)
			(layers "F.Cu" "F.Mask" "F.Paste")
			(net 687 "VDDQ")
			(pinfunction "VCCO_65")
			(pintype "power_in")
			(solder_mask_margin 0.075)
		)
		(pad "P23" smd circle
			(at 9.5 0.5 90)
			(size 0.5 0.5)
			(layers "F.Cu" "F.Mask" "F.Paste")
			(net 451 "/DDR5 RDIMM/B.DQS4_N")
			(pinfunction "IO_L22N_T3U_N7_DBC_AD0N_D05_65")
			(pintype "bidirectional")
			(die_length 10.717)
			(solder_mask_margin 0.075)
		)
		(pad "P24" smd circle
			(at 10.5 0.5 90)
			(size 0.5 0.5)
			(layers "F.Cu" "F.Mask" "F.Paste")
			(net 200 "/DDR5 RDIMM/B.CA5")
			(pinfunction "IO_L15N_T2L_N5_AD11N_A03_D19_65")
			(pintype "bidirectional")
			(die_length 11.277)
			(solder_mask_margin 0.075)
		)
		(pad "P25" smd circle
			(at 11.5 0.5 90)
			(size 0.5 0.5)
			(layers "F.Cu" "F.Mask" "F.Paste")
			(net 81 "/DDR5 RDIMM/B.CA4")
			(pinfunction "IO_L17P_T2U_N8_AD10P_D14_65")
			(pintype "bidirectional")
			(die_length 11.308)
			(solder_mask_margin 0.075)
		)
		(pad "P26" smd circle
			(at 12.5 0.5 90)
			(size 0.5 0.5)
			(layers "F.Cu" "F.Mask" "F.Paste")
			(net 199 "/DDR5 RDIMM/B.CA3")
			(pinfunction "IO_L17N_T2U_N9_AD10N_D15_65")
			(pintype "bidirectional")
			(die_length 11.915)
			(solder_mask_margin 0.075)
		)
		(pad "R1" smd circle
			(at -12.5 1.5 90)
			(size 0.5 0.5)
			(layers "F.Cu" "F.Mask" "F.Paste")
			(net 1 "GND")
			(pinfunction "GND")
			(pintype "passive")
			(solder_mask_margin 0.075)
		)
		(pad "R2" smd circle
			(at -11.5 1.5 90)
			(size 0.5 0.5)
			(layers "F.Cu" "F.Mask" "F.Paste")
			(net 1 "GND")
			(pinfunction "GND")
			(pintype "passive")
			(solder_mask_margin 0.075)
		)
		(pad "R3" smd circle
			(at -10.5 1.5 90)
			(size 0.5 0.5)
			(layers "F.Cu" "F.Mask" "F.Paste")
			(net 1 "GND")
			(pinfunction "GND")
			(pintype "passive")
			(solder_mask_margin 0.075)
		)
		(pad "R4" smd circle
			(at -9.5 1.5 90)
			(size 0.5 0.5)
			(layers "F.Cu" "F.Mask" "F.Paste")
			(net 28 "/FPGA MGT Interface/GTY_225_TX3_N")
			(pinfunction "MGTYTXN3_225")
			(pintype "output")
			(die_length 7.973)
			(solder_mask_margin 0.075)
		)
		(pad "R5" smd circle
			(at -8.5 1.5 90)
			(size 0.5 0.5)
			(layers "F.Cu" "F.Mask" "F.Paste")
			(net 22 "/FPGA MGT Interface/GTY_225_TX3_P")
			(pinfunction "MGTYTXP3_225")
			(pintype "output")
			(die_length 7.991)
			(solder_mask_margin 0.075)
		)
		(pad "R6" smd circle
			(at -7.5 1.5 90)
			(size 0.5 0.5)
			(layers "F.Cu" "F.Mask" "F.Paste")
			(net 1 "GND")
			(pinfunction "GND")
			(pintype "passive")
			(solder_mask_margin 0.075)
		)
		(pad "R7" smd circle
			(at -6.5 1.5 90)
			(size 0.5 0.5)
			(layers "F.Cu" "F.Mask" "F.Paste")
			(net 573 "+1V8_MGTVCCAUX")
			(pinfunction "MGTVCCAUX_R")
			(pintype "power_in")
			(solder_mask_margin 0.075)
		)
		(pad "R8" smd circle
			(at -5.5 1.5 90)
			(size 0.5 0.5)
			(layers "F.Cu" "F.Mask" "F.Paste")
			(net 1 "GND")
			(pinfunction "GND")
			(pintype "passive")
			(solder_mask_margin 0.075)
		)
		(pad "R9" smd circle
			(at -4.5 1.5 90)
			(size 0.5 0.5)
			(layers "F.Cu" "F.Mask" "F.Paste")
			(net 553 "+0V85")
			(pinfunction "VCCBRAM")
			(pintype "power_in")
			(solder_mask_margin 0.075)
		)
		(pad "R10" smd circle
			(at -3.5 1.5 90)
			(size 0.5 0.5)
			(layers "F.Cu" "F.Mask" "F.Paste")
			(net 553 "+0V85")
			(pinfunction "VCCINT")
			(pintype "passive")
			(solder_mask_margin 0.075)
		)
		(pad "R11" smd circle
			(at -2.5 1.5 90)
			(size 0.5 0.5)
			(layers "F.Cu" "F.Mask" "F.Paste")
			(net 1 "GND")
			(pinfunction "GND")
			(pintype "passive")
			(solder_mask_margin 0.075)
		)
		(pad "R12" smd circle
			(at -1.5 1.5 90)
			(size 0.5 0.5)
			(layers "F.Cu" "F.Mask" "F.Paste")
			(net 553 "+0V85")
			(pinfunction "VCCINT")
			(pintype "passive")
			(solder_mask_margin 0.075)
		)
		(pad "R13" smd circle
			(at -0.5 1.5 90)
			(size 0.5 0.5)
			(layers "F.Cu" "F.Mask" "F.Paste")
			(net 1 "GND")
			(pinfunction "VN")
			(pintype "input")
			(die_length 10.19)
			(solder_mask_margin 0.075)
		)
		(pad "R14" smd circle
			(at 0.5 1.5 90)
			(size 0.5 0.5)
			(layers "F.Cu" "F.Mask" "F.Paste")
			(net 599 "/FPGA Config/VREFP")
			(pinfunction "VREFP")
			(pintype "input")
			(die_length 12.277)
			(solder_mask_margin 0.075)
		)
		(pad "R15" smd circle
			(at 1.5 1.5 90)
			(size 0.5 0.5)
			(layers "F.Cu" "F.Mask" "F.Paste")
			(net 1 "GND")
			(pinfunction "GND")
			(pintype "passive")
			(solder_mask_margin 0.075)
		)
		(pad "R16" smd circle
			(at 2.5 1.5 90)
			(size 0.5 0.5)
			(layers "F.Cu" "F.Mask" "F.Paste")
			(net 553 "+0V85")
			(pinfunction "VCCINT")
			(pintype "passive")
			(solder_mask_margin 0.075)
		)
	)
)
